(kicad_pcb
	(version 20240108)
	(generator "pcbnew")
	(generator_version "8.0")
	(general
		(thickness 1.586)
		(legacy_teardrops no)
	)
	(paper "A4")
	(title_block
		(title "GMSL Serializer")
		(date "2024-11-27")
		(rev "1.1.1")
		(company "Antmicro Ltd")
		(comment 1 "www.antmicro.com")
		(comment 9 "footprints 29-31 of 117")
	)
	(layers
		(0 "F.Cu" signal)
		(1 "In1.Cu" power)
		(2 "In2.Cu" power)
		(31 "B.Cu" signal)
		(32 "B.Adhes" user "B.Adhesive")
		(33 "F.Adhes" user "F.Adhesive")
		(34 "B.Paste" user)
		(35 "F.Paste" user)
		(36 "B.SilkS" user "B.Silkscreen")
		(37 "F.SilkS" user "F.Silkscreen")
		(38 "B.Mask" user)
		(39 "F.Mask" user)
		(40 "Dwgs.User" user "User.Drawings")
		(41 "Cmts.User" user "User.Comments")
		(42 "Eco1.User" user "User.Eco1")
		(43 "Eco2.User" user "User.Eco2")
		(44 "Edge.Cuts" user)
		(45 "Margin" user)
		(46 "B.CrtYd" user "B.Courtyard")
		(47 "F.CrtYd" user "F.Courtyard")
		(48 "B.Fab" user)
		(49 "F.Fab" user)
	)
	(footprint "antmicro-footprints:R_0402_1005Metric"
		(layer "F.Cu")
		(at 146.55 115.995 90)
		(descr "Resistor SMD 0402")
		(tags "resistor SMD 0402")
		(property "Reference" "R39"
			(at -2.955 0.275 90)
			(layer "F.SilkS")
			(effects
				(font
					(size 0.7 0.7)
					(thickness 0.15)
				)
				(justify left bottom)
			)
		)
		(property "Value" "R_470R_0402"
			(at -1.011843 1.772047 90)
			(layer "F.Fab")
			(effects
				(font
					(size 0.7 0.7)
					(thickness 0.15)
				)
				(justify left bottom)
			)
		)
		(property "Footprint" "antmicro-footprints:R_0402_1005Metric"
			(at 0 0 90)
			(layer "F.Fab")
			(hide yes)
			(effects
				(font
					(size 1.27 1.27)
					(thickness 0.15)
				)
			)
		)
		(property "Datasheet" "https://www.bourns.com/docs/product-datasheets/cr.pdf"
			(at 0 0 90)
			(layer "F.Fab")
			(hide yes)
			(effects
				(font
					(size 1.27 1.27)
					(thickness 0.15)
				)
			)
		)
		(property "Author" "Antmicro"
			(at 262.545 -30.555 0)
			(layer "F.Fab")
			(hide yes)
			(effects
				(font
					(size 1 1)
					(thickness 0.15)
				)
			)
		)
		(property "License" "Apache-2.0"
			(at 262.545 -30.555 0)
			(layer "F.Fab")
			(hide yes)
			(effects
				(font
					(size 1 1)
					(thickness 0.15)
				)
			)
		)
		(property "MPN" "CR0402-FX-4700GLF"
			(at 262.545 -30.555 0)
			(layer "F.Fab")
			(hide yes)
			(effects
				(font
					(size 1 1)
					(thickness 0.15)
				)
			)
		)
		(property "Manufacturer" "Bourns"
			(at 262.545 -30.555 0)
			(layer "F.Fab")
			(hide yes)
			(effects
				(font
					(size 1 1)
					(thickness 0.15)
				)
			)
		)
		(property "Tolerance" "1%"
			(at 262.545 -30.555 0)
			(layer "F.Fab")
			(hide yes)
			(effects
				(font
					(size 1 1)
					(thickness 0.15)
				)
			)
		)
		(property "Val" "470R"
			(at 262.545 -30.555 0)
			(layer "F.Fab")
			(hide yes)
			(effects
				(font
					(size 1 1)
					(thickness 0.15)
				)
			)
		)
		(sheetname "Supply")
		(sheetfile "supply.kicad_sch")
		(attr smd)
		(fp_rect
			(start -0.925 -0.47)
			(end 0.925 0.47)
			(stroke
				(width 0.05)
				(type default)
			)
			(fill none)
			(layer "F.CrtYd")
		)
		(fp_rect
			(start -0.5 -0.25)
			(end 0.5 0.25)
			(stroke
				(width 0.15)
				(type solid)
			)
			(fill none)
			(layer "F.Fab")
		)
		(fp_text user "Author: Antmicro"
			(at -0.95 4.169 90)
			(layer "F.Fab")
			(hide yes)
			(effects
				(font
					(size 0.7 0.7)
					(thickness 0.15)
				)
				(justify left bottom)
			)
		)
		(fp_text user "License: Apache-2.0"
			(at -0.95 5.169 90)
			(layer "F.Fab")
			(hide yes)
			(effects
				(font
					(size 0.7 0.7)
					(thickness 0.15)
				)
				(justify left bottom)
			)
		)
		(fp_text user "${REFERENCE}"
			(at -0.95 3.168 90)
			(layer "F.Fab")
			(hide yes)
			(effects
				(font
					(size 0.7 0.7)
					(thickness 0.15)
				)
				(justify left bottom)
			)
		)
		(pad "1" smd roundrect
			(at -0.48 0 90)
			(size 0.59 0.64)
			(layers "F.Cu" "F.Paste" "F.Mask")
			(roundrect_rratio 0.25)
			(net 74 "Net-(D8-A)")
			(pintype "passive")
		)
		(pad "2" smd roundrect
			(at 0.48 0 90)
			(size 0.59 0.64)
			(layers "F.Cu" "F.Paste" "F.Mask")
			(roundrect_rratio 0.25)
			(net 9 "+5V")
			(pintype "passive")
		)
	)
	(footprint "antmicro-footprints:R_0402_1005Metric"
		(layer "F.Cu")
		(at 151.775 96.675 -135)
		(descr "Resistor SMD 0402")
		(tags "resistor SMD 0402")
		(property "Reference" "R29"
			(at -2.821356 -0.445477 45)
			(layer "F.SilkS")
			(effects
				(font
					(size 0.7 0.7)
					(thickness 0.15)
				)
				(justify left bottom)
			)
		)
		(property "Value" "R_51R_0402"
			(at -1.011843 1.772046 45)
			(layer "F.Fab")
			(effects
				(font
					(size 0.7 0.7)
					(thickness 0.15)
				)
				(justify right bottom)
			)
		)
		(property "Footprint" "antmicro-footprints:R_0402_1005Metric"
			(at 0 0 -135)
			(layer "F.Fab")
			(hide yes)
			(effects
				(font
					(size 1.27 1.27)
					(thickness 0.15)
				)
			)
		)
		(property "Datasheet" "https://www.bourns.com/docs/product-datasheets/cr.pdf"
			(at 0 0 -135)
			(layer "F.Fab")
			(hide yes)
			(effects
				(font
					(size 1.27 1.27)
					(thickness 0.15)
				)
			)
		)
		(property "Author" "Antmicro"
			(at 190.736584 272.35568 0)
			(layer "F.Fab")
			(hide yes)
			(effects
				(font
					(size 1 1)
					(thickness 0.15)
				)
			)
		)
		(property "License" "Apache-2.0"
			(at 190.736584 272.35568 0)
			(layer "F.Fab")
			(hide yes)
			(effects
				(font
					(size 1 1)
					(thickness 0.15)
				)
			)
		)
		(property "MPN" "CR0402-FX-51R0GLF"
			(at 190.736584 272.35568 0)
			(layer "F.Fab")
			(hide yes)
			(effects
				(font
					(size 1 1)
					(thickness 0.15)
				)
			)
		)
		(property "Manufacturer" "Bourns"
			(at 190.736584 272.35568 0)
			(layer "F.Fab")
			(hide yes)
			(effects
				(font
					(size 1 1)
					(thickness 0.15)
				)
			)
		)
		(property "Tolerance" "1%"
			(at 190.736584 272.35568 0)
			(layer "F.Fab")
			(hide yes)
			(effects
				(font
					(size 1 1)
					(thickness 0.15)
				)
			)
		)
		(property "Val" "51R"
			(at 190.736584 272.35568 0)
			(layer "F.Fab")
			(hide yes)
			(effects
				(font
					(size 1 1)
					(thickness 0.15)
				)
			)
		)
		(sheetname "Serializer")
		(sheetfile "serializer.kicad_sch")
		(attr smd)
		(fp_poly
			(pts
				(xy -0.925 -0.47) (xy 0.925 -0.47) (xy 0.925 0.47) (xy -0.925 0.47)
			)
			(stroke
				(width 0.05)
				(type default)
			)
			(fill none)
			(layer "F.CrtYd")
		)
		(fp_poly
			(pts
				(xy -0.5 -0.25) (xy 0.5 -0.25) (xy 0.5 0.25) (xy -0.5 0.25)
			)
			(stroke
				(width 0.15)
				(type solid)
			)
			(fill none)
			(layer "F.Fab")
		)
		(fp_text user "Author: Antmicro"
			(at -0.95 4.169 45)
			(layer "F.Fab")
			(hide yes)
			(effects
				(font
					(size 0.7 0.7)
					(thickness 0.15)
				)
				(justify right bottom)
			)
		)
		(fp_text user "License: Apache-2.0"
			(at -0.949999 5.169 45)
			(layer "F.Fab")
			(hide yes)
			(effects
				(font
					(size 0.7 0.7)
					(thickness 0.15)
				)
				(justify right bottom)
			)
		)
		(fp_text user "${REFERENCE}"
			(at -0.95 3.168 45)
			(layer "F.Fab")
			(hide yes)
			(effects
				(font
					(size 0.7 0.7)
					(thickness 0.15)
				)
				(justify right bottom)
			)
		)
		(pad "1" smd roundrect
			(at -0.48 0 225)
			(size 0.59 0.64)
			(layers "F.Cu" "F.Paste" "F.Mask")
			(roundrect_rratio 0.25)
			(net 1 "GND")
			(pintype "passive")
		)
		(pad "2" smd roundrect
			(at 0.48 0 225)
			(size 0.59 0.64)
			(layers "F.Cu" "F.Paste" "F.Mask")
			(roundrect_rratio 0.25)
			(net 16 "Net-(C31-Pad2)")
			(pintype "passive")
		)
	)
	(footprint "antmicro-footprints:LED_0603_1608Metric_G"
		(layer "F.Cu")
		(at 139.5 115.75 -90)
		(descr "LED SMD 0603 Green")
		(tags "LED SMD 0603 Green")
		(property "Reference" "D9"
			(at -2.7 -0.5 90)
			(layer "F.SilkS")
			(effects
				(font
					(size 0.7 0.7)
					(thickness 0.15)
				)
				(justify right bottom)
			)
		)
		(property "Value" "LED_G_0603_LTST-C190GKT"
			(at -0.001 1.599 90)
			(layer "F.Fab")
			(effects
				(font
					(size 0.7 0.7)
					(thickness 0.15)
				)
				(justify right bottom)
			)
		)
		(property "Footprint" "antmicro-footprints:LED_0603_1608Metric_G"
			(at 0 0 -90)
			(layer "F.Fab")
			(hide yes)
			(effects
				(font
					(size 1.27 1.27)
					(thickness 0.15)
				)
			)
		)
		(property "Datasheet" "https://media.digikey.com/pdf/Data%20Sheets/Lite-On%20PDFs/LTST-C190GKT.pdf"
			(at 0 0 -90)
			(layer "F.Fab")
			(hide yes)
			(effects
				(font
					(size 1.27 1.27)
					(thickness 0.15)
				)
			)
		)
		(property "Author" "Antmicro"
			(at 23.75 255.25 0)
			(layer "F.Fab")
			(hide yes)
			(effects
				(font
					(size 1 1)
					(thickness 0.15)
				)
			)
		)
		(property "Color" "Green"
			(at 23.75 255.25 0)
			(layer "F.Fab")
			(hide yes)
			(effects
				(font
					(size 1 1)
					(thickness 0.15)
				)
			)
		)
		(property "License" "Apache-2.0"
			(at 23.75 255.25 0)
			(layer "F.Fab")
			(hide yes)
			(effects
				(font
					(size 1 1)
					(thickness 0.15)
				)
			)
		)
		(property "MPN" "LTST-C190GKT"
			(at 23.75 255.25 0)
			(layer "F.Fab")
			(hide yes)
			(effects
				(font
					(size 1 1)
					(thickness 0.15)
				)
			)
		)
		(property "Manufacturer" "Lite-On"
			(at 23.75 255.25 0)
			(layer "F.Fab")
			(hide yes)
			(effects
				(font
					(size 1 1)
					(thickness 0.15)
				)
			)
		)
		(property "VSD_class" "LED"
			(at 23.75 255.25 0)
			(layer "F.Fab")
			(hide yes)
			(effects
				(font
					(size 1 1)
					(thickness 0.15)
				)
			)
		)
		(sheetname "Supply")
		(sheetfile "supply.kicad_sch")
		(attr smd)
		(fp_line
			(start 0.22 0.35)
			(end -0.22 0.35)
			(stroke
				(width 0.15)
				(type solid)
			)
			(layer "F.SilkS")
		)
		(fp_line
			(start -0.094672 0.201008)
			(end -0.094672 -0.198992)
			(stroke
				(width 0.1)
				(type solid)
			)
			(layer "F.SilkS")
		)
		(fp_line
			(start 0.105328 0.201008)
			(end -0.094672 0.001008)
			(stroke
				(width 0.1)
				(type solid)
			)
			(layer "F.SilkS")
		)
		(fp_line
			(start 0.105328 0.201008)
			(end 0.105328 -0.198992)
			(stroke
				(width 0.1)
				(type solid)
			)
			(layer "F.SilkS")
		)
		(fp_line
			(start -0.094672 0.001008)
			(end -0.24 0.001008)
			(stroke
				(width 0.1)
				(type solid)
			)
			(layer "F.SilkS")
		)
		(fp_line
			(start -0.094672 0.001008)
			(end 0.105328 -0.198992)
			(stroke
				(width 0.1)
				(type solid)
			)
			(layer "F.SilkS")
		)
		(fp_line
			(start 0.105328 0.001008)
			(end 0.24 0.001)
			(stroke
				(width 0.1)
				(type solid)
			)
			(layer "F.SilkS")
		)
		(fp_line
			(start -1.18 -0.319)
			(end -1.18 0.321)
			(stroke
				(width 0.15)
				(type solid)
			)
			(layer "F.SilkS")
		)
		(fp_line
			(start 0.22 -0.35)
			(end -0.22 -0.35)
			(stroke
				(width 0.15)
				(type solid)
			)
			(layer "F.SilkS")
		)
		(fp_rect
			(start 1.25 0.65)
			(end -1.25 -0.65)
			(stroke
				(width 0.05)
				(type solid)
			)
			(fill none)
			(layer "F.CrtYd")
		)
		(fp_line
			(start -0.199 0.2)
			(end -0.199 0.1)
			(stroke
				(width 0.15)
				(type solid)
			)
			(layer "F.Fab")
		)
		(fp_line
			(start 0.201 0.2)
			(end 0.201 0)
			(stroke
				(width 0.15)
				(type solid)
			)
			(layer "F.Fab")
		)
		(fp_line
			(start -0.199 0)
			(end -0.597 0)
			(stroke
				(width 0.15)
				(type solid)
			)
			(layer "F.Fab")
		)
		(fp_line
			(start -0.101 0)
			(end 0.201 0.2)
			(stroke
				(width 0.15)
				(type solid)
			)
			(layer "F.Fab")
		)
		(fp_line
			(start 0.201 0)
			(end 0.201 -0.202)
			(stroke
				(width 0.15)
				(type solid)
			)
			(layer "F.Fab")
		)
		(fp_line
			(start 0.599 0)
			(end 0.201 0)
			(stroke
				(width 0.15)
				(type solid)
			)
			(layer "F.Fab")
		)
		(fp_line
			(start -0.199 -0.202)
			(end -0.199 0.1)
			(stroke
				(width 0.15)
				(type solid)
			)
			(layer "F.Fab")
		)
		(fp_line
			(start 0.201 -0.202)
			(end -0.101 0)
			(stroke
				(width 0.15)
				(type solid)
			)
			(layer "F.Fab")
		)
		(fp_rect
			(start 0.848 0.4)
			(end -0.85 -0.402)
			(stroke
				(width 0.15)
				(type solid)
			)
			(fill none)
			(layer "F.Fab")
		)
		(fp_text user "Author: Antmicro"
			(at -1.4224 4.799 90)
			(layer "F.Fab")
			(hide yes)
			(effects
				(font
					(size 0.7 0.7)
					(thickness 0.15)
				)
				(justify right bottom)
			)
		)
		(fp_text user "${REFERENCE}"
			(at -1.4224 5.999 90)
			(layer "F.Fab")
			(hide yes)
			(effects
				(font
					(size 0.7 0.7)
					(thickness 0.15)
				)
				(justify right bottom)
			)
		)
		(fp_text user "License: Apache-2.0"
			(at -1.4224 3.599 90)
			(layer "F.Fab")
			(hide yes)
			(effects
				(font
					(size 0.7 0.7)
					(thickness 0.15)
				)
				(justify right bottom)
			)
		)
		(pad "1" smd roundrect
			(at -0.7 0 90)
			(size 0.8 1)
			(layers "F.Cu" "F.Paste" "F.Mask")
			(roundrect_rratio 0.2)
			(net 75 "Net-(D9-C)")
			(pinfunction "C")
			(pintype "passive")
		)
		(pad "2" smd roundrect
			(at 0.7 0 90)
			(size 0.8 1)
			(layers "F.Cu" "F.Paste" "F.Mask")
			(roundrect_rratio 0.2)
			(net 2 "+12V")
			(pinfunction "A")
			(pintype "passive")
		)
	)
)
